(kicad_pcb
	(version 20221018)
	(generator pcbnew)
	(general
    (thickness 1.7403)
  )
	(paper "A4")
	(title_block
    (title "Data Center RDIMM DDR4 Tester")
    (date "2024-09-30")
    (rev "1.2.4")
		(comment 9 "footprints 638-644 of 690")
	)
	(layers
    (0 "F.Cu" signal)
    (1 "In1.Cu" power)
    (2 "In2.Cu" signal)
    (3 "In3.Cu" power)
    (4 "In4.Cu" power)
    (5 "In5.Cu" signal)
    (6 "In6.Cu" power)
    (7 "In7.Cu" signal)
    (8 "In8.Cu" power)
    (9 "In9.Cu" signal)
    (10 "In10.Cu" power)
    (31 "B.Cu" signal)
    (32 "B.Adhes" user "B.Adhesive")
    (33 "F.Adhes" user "F.Adhesive")
    (34 "B.Paste" user)
    (35 "F.Paste" user)
    (36 "B.SilkS" user "B.Silkscreen")
    (37 "F.SilkS" user "F.Silkscreen")
    (38 "B.Mask" user)
    (39 "F.Mask" user)
    (40 "Dwgs.User" user "User.Drawings")
    (41 "Cmts.User" user "User.Comments")
    (42 "Eco1.User" user "User.Eco1")
    (43 "Eco2.User" user "User.Eco2")
    (44 "Edge.Cuts" user)
    (45 "Margin" user)
    (46 "B.CrtYd" user "B.Courtyard")
    (47 "F.CrtYd" user "F.Courtyard")
    (48 "B.Fab" user)
    (49 "F.Fab" user)
  )
	(footprint "data-center-rdimm-ddr4-tester-footprints:C_0201" (layer "B.Cu")
    (at 177.85 101.56 180)
    (descr "Capacitor SMD 0201")
    (tags "capacitor SMD 0201")
    (property "Author" "Antmicro")
    (property "Dielectric" "")
    (property "License" "Apache-2.0")
    (property "MPN" "CC0201KRX6S5BB104")
    (property "Manufacturer" "Yaego")
    (property "Sheetfile" "fpga-power.kicad_sch")
    (property "Sheetname" "FPGA power")
    (property "Val" "100n")
    (property "Voltage" "")
    (property "ki_description" " ")
    (attr smd)
    (fp_text reference "C83" (at -1.09 0.46) (layer "B.SilkS")
        (effects (font (size 0.7 0.7) (thickness 0.15)) (justify left bottom mirror))
    )
    (fp_text value "C_100n_0201" (at 0 -1.4) (layer "B.Fab") hide
        (effects (font (size 0.7 0.7) (thickness 0.15)) (justify left bottom mirror))
    )
    (fp_text user "License: Apache-2.0" (at -0.72 -4.4) (layer "B.Fab") hide
        (effects (font (size 0.7 0.7) (thickness 0.15)) (justify left bottom mirror))
    )
    (fp_text user "Author: Antmicro" (at -0.72 -5.4) (layer "B.Fab") hide
        (effects (font (size 0.7 0.7) (thickness 0.15)) (justify left bottom mirror))
    )
    (fp_text user "${REFERENCE}" (at -0.72 -3.4) (layer "B.Fab") hide
        (effects (font (size 0.7 0.7) (thickness 0.15)) (justify left bottom mirror))
    )
    (fp_rect (start -0.72 0.38) (end 0.72 -0.38)
      (stroke (width 0.05) (type solid)) (fill none) (layer "B.CrtYd"))
    (fp_rect (start 0.3 -0.15) (end -0.301 0.149)
      (stroke (width 0.15) (type solid)) (fill none) (layer "B.Fab"))
    (pad "" smd roundrect (at -0.349 0.002 180) (size 0.318 0.36) (layers "B.Paste") (roundrect_rratio 0.25))
    (pad "" smd roundrect (at 0.341 0.002 180) (size 0.318 0.36) (layers "B.Paste") (roundrect_rratio 0.25))
    (pad "1" smd roundrect (at -0.321 0.002 180) (size 0.46 0.4) (layers "B.Cu" "B.Mask") (roundrect_rratio 0.25)
      (net 143 "3V3_SYS") (pintype "passive"))
    (pad "2" smd roundrect (at 0.32 0.002 180) (size 0.46 0.4) (layers "B.Cu" "B.Mask") (roundrect_rratio 0.25)
      (net 9 "GND") (pintype "passive"))
  )
	(footprint "data-center-rdimm-ddr4-tester-footprints:C_0201" (layer "B.Cu")
    (at 171.075 78.1 -90)
    (descr "Capacitor SMD 0201")
    (tags "capacitor SMD 0201")
    (property "Author" "Antmicro")
    (property "Dielectric" "")
    (property "License" "Apache-2.0")
    (property "MPN" "CC0201KRX6S5BB104")
    (property "Manufacturer" "Yaego")
    (property "Sheetfile" "fpga-power.kicad_sch")
    (property "Sheetname" "FPGA power")
    (property "Val" "100n")
    (property "Voltage" "")
    (property "ki_description" " ")
    (attr smd)
    (fp_text reference "C90" (at -1.1 0.425 90) (layer "B.SilkS")
        (effects (font (size 0.7 0.7) (thickness 0.15)) (justify left bottom mirror))
    )
    (fp_text value "C_100n_0201" (at 0 -1.4 90) (layer "B.Fab") hide
        (effects (font (size 0.7 0.7) (thickness 0.15)) (justify left bottom mirror))
    )
    (fp_text user "Author: Antmicro" (at -0.72 -5.4 90) (layer "B.Fab") hide
        (effects (font (size 0.7 0.7) (thickness 0.15)) (justify left bottom mirror))
    )
    (fp_text user "License: Apache-2.0" (at -0.72 -4.4 90) (layer "B.Fab") hide
        (effects (font (size 0.7 0.7) (thickness 0.15)) (justify left bottom mirror))
    )
    (fp_text user "${REFERENCE}" (at -0.72 -3.4 90) (layer "B.Fab") hide
        (effects (font (size 0.7 0.7) (thickness 0.15)) (justify left bottom mirror))
    )
    (fp_rect (start -0.72 0.38) (end 0.72 -0.38)
      (stroke (width 0.05) (type solid)) (fill none) (layer "B.CrtYd"))
    (fp_rect (start 0.3 -0.15) (end -0.301 0.149)
      (stroke (width 0.15) (type solid)) (fill none) (layer "B.Fab"))
    (pad "" smd roundrect (at -0.349 0.002 270) (size 0.318 0.36) (layers "B.Paste") (roundrect_rratio 0.25))
    (pad "" smd roundrect (at 0.341 0.002 270) (size 0.318 0.36) (layers "B.Paste") (roundrect_rratio 0.25))
    (pad "1" smd roundrect (at -0.321 0.002 270) (size 0.46 0.4) (layers "B.Cu" "B.Mask") (roundrect_rratio 0.25)
      (net 143 "3V3_SYS") (pintype "passive"))
    (pad "2" smd roundrect (at 0.32 0.002 270) (size 0.46 0.4) (layers "B.Cu" "B.Mask") (roundrect_rratio 0.25)
      (net 9 "GND") (pintype "passive"))
  )
	(footprint "data-center-rdimm-ddr4-tester-footprints:C_0201" (layer "B.Cu")
    (at 196.1 100.525)
    (descr "Capacitor SMD 0201")
    (tags "capacitor SMD 0201")
    (property "Author" "Antmicro")
    (property "Dielectric" "")
    (property "License" "Apache-2.0")
    (property "MPN" "CC0201KRX6S5BB104")
    (property "Manufacturer" "Yaego")
    (property "Sheetfile" "fpga-power.kicad_sch")
    (property "Sheetname" "FPGA power")
    (property "Val" "100n")
    (property "Voltage" "")
    (property "ki_description" " ")
    (attr smd)
    (fp_text reference "C255" (at 3.43 0.365 180) (layer "B.SilkS")
        (effects (font (size 0.7 0.7) (thickness 0.15)) (justify left bottom mirror))
    )
    (fp_text value "C_100n_0201" (at 0 -1.4 180) (layer "B.Fab") hide
        (effects (font (size 0.7 0.7) (thickness 0.15)) (justify left bottom mirror))
    )
    (fp_text user "Author: Antmicro" (at -0.72 -5.4 180) (layer "B.Fab") hide
        (effects (font (size 0.7 0.7) (thickness 0.15)) (justify left bottom mirror))
    )
    (fp_text user "License: Apache-2.0" (at -0.72 -4.4 180) (layer "B.Fab") hide
        (effects (font (size 0.7 0.7) (thickness 0.15)) (justify left bottom mirror))
    )
    (fp_text user "${REFERENCE}" (at -0.72 -3.4 180) (layer "B.Fab") hide
        (effects (font (size 0.7 0.7) (thickness 0.15)) (justify left bottom mirror))
    )
    (fp_rect (start -0.72 0.38) (end 0.72 -0.38)
      (stroke (width 0.05) (type solid)) (fill none) (layer "B.CrtYd"))
    (fp_rect (start 0.3 -0.15) (end -0.301 0.149)
      (stroke (width 0.15) (type solid)) (fill none) (layer "B.Fab"))
    (pad "" smd roundrect (at -0.349 0.002) (size 0.318 0.36) (layers "B.Paste") (roundrect_rratio 0.25))
    (pad "" smd roundrect (at 0.341 0.002) (size 0.318 0.36) (layers "B.Paste") (roundrect_rratio 0.25))
    (pad "1" smd roundrect (at -0.321 0.002) (size 0.46 0.4) (layers "B.Cu" "B.Mask") (roundrect_rratio 0.25)
      (net 306 "1V2_SYS") (pintype "passive"))
    (pad "2" smd roundrect (at 0.32 0.002) (size 0.46 0.4) (layers "B.Cu" "B.Mask") (roundrect_rratio 0.25)
      (net 9 "GND") (pintype "passive"))
  )
	(footprint "data-center-rdimm-ddr4-tester-footprints:C_0402_1005Metric" (layer "B.Cu")
    (at 119.67 99.499)
    (descr "Capacitor SMD 0402")
    (tags "capacitor SMD 0402")
    (property "Author" "Antmicro")
    (property "Dielectric" "X5R")
    (property "License" "Apache-2.0")
    (property "MPN" "GRM155R61H104KE14D")
    (property "Manufacturer" "Murata")
    (property "Sheetfile" "supply.kicad_sch")
    (property "Sheetname" "Supply")
    (property "Val" "100n")
    (property "Voltage" "50V")
    (property "ki_description" " ")
    (attr smd)
    (fp_text reference "C237" (at 1.42 1.351 180) (layer "B.SilkS")
        (effects (font (size 0.7 0.7) (thickness 0.15)) (justify left bottom mirror))
    )
    (fp_text value "C_100n_0402" (at 0 -1.4 180) (layer "B.Fab") hide
        (effects (font (size 0.7 0.7) (thickness 0.15)) (justify left bottom mirror))
    )
    (fp_text user "Author: Antmicro" (at -0.932 -4.17 180) (layer "B.Fab") hide
        (effects (font (size 0.7 0.7) (thickness 0.15)) (justify left bottom mirror))
    )
    (fp_text user "License: Apache-2.0" (at -0.932 -5.17 180) (layer "B.Fab") hide
        (effects (font (size 0.7 0.7) (thickness 0.15)) (justify left bottom mirror))
    )
    (fp_text user "${REFERENCE}" (at -0.932 -3.168 180) (layer "B.Fab") hide
        (effects (font (size 0.7 0.7) (thickness 0.15)) (justify left bottom mirror))
    )
    (fp_rect (start -0.94 0.47) (end 0.94 -0.47)
      (stroke (width 0.05) (type solid)) (fill none) (layer "B.CrtYd"))
    (fp_rect (start -0.499 0.249) (end 0.499 -0.249)
      (stroke (width 0.15) (type solid)) (fill none) (layer "B.Fab"))
    (pad "1" smd roundrect (at -0.484 0) (size 0.59 0.64) (layers "B.Cu" "B.Paste" "B.Mask") (roundrect_rratio 0.25)
      (net 307 "5V0_SYS") (pintype "passive"))
    (pad "2" smd roundrect (at 0.484 0) (size 0.59 0.64) (layers "B.Cu" "B.Paste" "B.Mask") (roundrect_rratio 0.25)
      (net 9 "GND") (pintype "passive"))
  )
	(footprint "data-center-rdimm-ddr4-tester-footprints:R_0402_1005Metric" (layer "B.Cu")
    (at 199.05 54.75 -90)
    (descr "Resistor SMD 0402")
    (tags "resistor SMD 0402")
    (property "Author" "Antmicro")
    (property "Current" "1A")
    (property "DNP" "DNP")
    (property "License" "Apache-2.0")
    (property "MPN" "ERJ2GE0R00X")
    (property "Manufacturer" "Panasonic")
    (property "Sheetfile" "DDR4.kicad_sch")
    (property "Sheetname" "DDR4")
    (property "Tolerance" "")
    (property "Val" "0R")
    (property "dnp" "")
    (property "exclude_from_bom" "")
    (property "ki_description" "0R resistor in 0402 package with unspecified tolerance")
    (attr exclude_from_pos_files exclude_from_bom)
    (fp_text reference "R185" (at -4.05 -0.4 90) (layer "B.SilkS")
        (effects (font (size 0.7 0.7) (thickness 0.15)) (justify left bottom mirror))
    )
    (fp_text value "R_0R_0402" (at 0 -1.4 90) (layer "B.Fab") hide
        (effects (font (size 0.7 0.7) (thickness 0.15)) (justify left bottom mirror))
    )
    (fp_text user "${REFERENCE}" (at -0.95 -3.168 90) (layer "B.Fab") hide
        (effects (font (size 0.7 0.7) (thickness 0.15)) (justify left bottom mirror))
    )
    (fp_text user "License: Apache-2.0" (at -0.95 -5.169 90) (layer "B.Fab") hide
        (effects (font (size 0.7 0.7) (thickness 0.15)) (justify left bottom mirror))
    )
    (fp_text user "Author: Antmicro" (at -0.95 -4.169 90) (layer "B.Fab") hide
        (effects (font (size 0.7 0.7) (thickness 0.15)) (justify left bottom mirror))
    )
    (fp_rect (start -0.93 0.47) (end 0.93 -0.47)
      (stroke (width 0.05) (type solid)) (fill none) (layer "B.CrtYd"))
    (fp_rect (start -0.5 0.25) (end 0.5 -0.25)
      (stroke (width 0.15) (type solid)) (fill none) (layer "B.Fab"))
    (pad "1" smd roundrect (at -0.485 0 270) (size 0.59 0.64) (layers "B.Cu" "B.Paste" "B.Mask") (roundrect_rratio 0.25)
      (net 9 "GND") (pintype "passive"))
    (pad "2" smd roundrect (at 0.485 0 270) (size 0.59 0.64) (layers "B.Cu" "B.Paste" "B.Mask") (roundrect_rratio 0.25)
      (net 789 "DDR_PRESENCE") (pintype "passive"))
  )
	(footprint "data-center-rdimm-ddr4-tester-footprints:MicroSD_Wurth_693071020811" (layer "B.Cu")
    (at 132.95 129.009 180)
    (descr "SMT MICRO SD CARD CONNECTOR")
    (property "Author" "Antmicro")
    (property "License" "Apache-2.0")
    (property "MPN" "693071020811")
    (property "Manufacturer" "Würth Elektronik")
    (property "Sheetfile" "interfaces.kicad_sch")
    (property "Sheetname" "Interfaces")
    (property "ki_description" "SMT MICRO SD CARD CONNECTOR, PUSH-PUSH")
    (attr smd)
    (fp_text reference "J7" (at -8.93 -6.131) (layer "B.SilkS")
        (effects (font (size 0.7 0.7) (thickness 0.15)) (justify left bottom mirror))
    )
    (fp_text value "MicroSD_693071020811" (at -8.5 -11.5) (layer "B.Fab") hide
        (effects (font (size 0.7 0.7) (thickness 0.15)) (justify left bottom mirror))
    )
    (fp_text user "Author: Antmicro" (at -8.5 -14.5) (layer "B.Fab") hide
        (effects (font (size 0.7 0.7) (thickness 0.15)) (justify left bottom mirror))
    )
    (fp_text user "${REFERENCE}" (at -8.5 -13) (layer "B.Fab") hide
        (effects (font (size 0.7 0.7) (thickness 0.15)) (justify left bottom mirror))
    )
    (fp_text user "License: Apache-2.0" (at -8.5 -16) (layer "B.Fab") hide
        (effects (font (size 0.7 0.7) (thickness 0.15)) (justify left bottom mirror))
    )
    (fp_line (start -7.351 -1.431) (end -7.351 5.268)
      (stroke (width 0.15) (type solid)) (layer "B.SilkS"))
    (fp_line (start 2.8 8.4) (end 2.8 7.149)
      (stroke (width 0.15) (type solid)) (layer "B.SilkS"))
    (fp_line (start 6.2 7.149) (end 2.8 7.149)
      (stroke (width 0.15) (type solid)) (layer "B.SilkS"))
    (fp_line (start 7.349 -1.431) (end 7.349 5.268)
      (stroke (width 0.15) (type solid)) (layer "B.SilkS"))
    (fp_line (start 2.7 -2.982) (end 3.398 -2.982)
      (stroke (width 0.01) (type solid)) (layer "Edge.Cuts"))
    (fp_line (start 3.398 -3.982) (end 2.7 -3.982)
      (stroke (width 0.01) (type solid)) (layer "Edge.Cuts"))
    (fp_arc (start 2.2 -3.482) (mid 2.346 -3.836) (end 2.7 -3.982)
      (stroke (width 0.01) (type solid)) (layer "Edge.Cuts"))
    (fp_arc (start 2.7 -2.982) (mid 2.346 -3.128) (end 2.2 -3.482)
      (stroke (width 0.01) (type solid)) (layer "Edge.Cuts"))
    (fp_arc (start 3.398 -3.982) (mid 3.752498 -3.836498) (end 3.898 -3.482)
      (stroke (width 0.01) (type solid)) (layer "Edge.Cuts"))
    (fp_arc (start 3.898 -3.482) (mid 3.752498 -3.127502) (end 3.398 -2.982)
      (stroke (width 0.01) (type solid)) (layer "Edge.Cuts"))
    (fp_line (start -9.1 7.6) (end -9.1 5.45)
      (stroke (width 0.05) (type solid)) (layer "B.CrtYd"))
    (fp_line (start -9.1 7.6) (end -7.05 7.6)
      (stroke (width 0.05) (type solid)) (layer "B.CrtYd"))
    (fp_line (start -8.7 -4.55) (end -8.7 -1.6)
      (stroke (width 0.05) (type solid)) (layer "B.CrtYd"))
    (fp_line (start -8.7 -4.55) (end -7.55 -4.55)
      (stroke (width 0.05) (type solid)) (layer "B.CrtYd"))
    (fp_line (start -7.55 -7.7) (end -7.55 -4.55)
      (stroke (width 0.05) (type solid)) (layer "B.CrtYd"))
    (fp_line (start -7.55 -1.6) (end -8.7 -1.6)
      (stroke (width 0.05) (type solid)) (layer "B.CrtYd"))
    (fp_line (start -7.55 5.45) (end -9.1 5.45)
      (stroke (width 0.05) (type solid)) (layer "B.CrtYd"))
    (fp_line (start -7.55 5.45) (end -7.55 -1.6)
      (stroke (width 0.05) (type solid)) (layer "B.CrtYd"))
    (fp_line (start -7.05 8.7) (end -7.05 7.6)
      (stroke (width 0.05) (type solid)) (layer "B.CrtYd"))
    (fp_line (start -7.05 8.7) (end 2.75 8.7)
      (stroke (width 0.05) (type solid)) (layer "B.CrtYd"))
    (fp_line (start 2.75 7.6) (end 2.75 8.7)
      (stroke (width 0.05) (type solid)) (layer "B.CrtYd"))
    (fp_line (start 7.5 -7.7) (end -7.55 -7.7)
      (stroke (width 0.05) (type solid)) (layer "B.CrtYd"))
    (fp_line (start 7.5 -7.7) (end 7.5 -4.55)
      (stroke (width 0.05) (type solid)) (layer "B.CrtYd"))
    (fp_line (start 7.5 -1.6) (end 7.5 5.45)
      (stroke (width 0.05) (type solid)) (layer "B.CrtYd"))
    (fp_line (start 7.5 -1.6) (end 8.7 -1.6)
      (stroke (width 0.05) (type solid)) (layer "B.CrtYd"))
    (fp_line (start 7.5 5.45) (end 8.4 5.45)
      (stroke (width 0.05) (type solid)) (layer "B.CrtYd"))
    (fp_line (start 8.4 7.6) (end 2.75 7.6)
      (stroke (width 0.05) (type solid)) (layer "B.CrtYd"))
    (fp_line (start 8.4 7.6) (end 8.4 5.45)
      (stroke (width 0.05) (type solid)) (layer "B.CrtYd"))
    (fp_line (start 8.7 -4.55) (end 7.5 -4.55)
      (stroke (width 0.05) (type solid)) (layer "B.CrtYd"))
    (fp_line (start 8.7 -4.55) (end 8.7 -1.6)
      (stroke (width 0.05) (type solid)) (layer "B.CrtYd"))
    (fp_line (start -7.351 -7.501) (end 7.349 -7.501)
      (stroke (width 0.15) (type solid)) (layer "B.Fab"))
    (fp_line (start -7.351 7.149) (end -7.351 -7.352)
      (stroke (width 0.15) (type solid)) (layer "B.Fab"))
    (fp_line (start 7.349 -7.352) (end 7.349 7.149)
      (stroke (width 0.15) (type solid)) (layer "B.Fab"))
    (fp_line (start 7.349 7.149) (end -7.351 7.149)
      (stroke (width 0.15) (type solid)) (layer "B.Fab"))
    (pad "" np_thru_hole circle (at -4.952 -3.482 180) (size 1 1) (drill 1) (layers "*.Cu" "*.Mask"))
    (pad "1" smd rect (at 2.249 7.569 180) (size 0.7 1.9) (layers "B.Cu" "B.Paste" "B.Mask")
      (net 87 "SD_DAT2") (pinfunction "DAT2") (pintype "bidirectional"))
    (pad "2" smd rect (at 1.148 7.569 180) (size 0.7 1.9) (layers "B.Cu" "B.Paste" "B.Mask")
      (net 86 "SD_DAT3") (pinfunction "DAT3/CD") (pintype "bidirectional"))
    (pad "3" smd rect (at 0.05 7.569 180) (size 0.7 1.9) (layers "B.Cu" "B.Paste" "B.Mask")
      (net 85 "SD_CMD") (pinfunction "CMD") (pintype "input"))
    (pad "4" smd rect (at -1.051 7.569 180) (size 0.7 1.9) (layers "B.Cu" "B.Paste" "B.Mask")
      (net 143 "3V3_SYS") (pinfunction "VDD") (pintype "power_in"))
    (pad "5" smd rect (at -2.15 7.569 180) (size 0.7 1.9) (layers "B.Cu" "B.Paste" "B.Mask")
      (net 84 "SD_CLK") (pinfunction "CLK") (pintype "input"))
    (pad "6" smd rect (at -3.25 7.569 180) (size 0.7 1.9) (layers "B.Cu" "B.Paste" "B.Mask")
      (net 9 "GND") (pinfunction "VSS") (pintype "passive"))
    (pad "7" smd rect (at -4.351 7.569 180) (size 0.7 1.9) (layers "B.Cu" "B.Paste" "B.Mask")
      (net 83 "SD_DAT0") (pinfunction "DAT0") (pintype "input"))
    (pad "8" smd rect (at -5.452 7.569 180) (size 0.7 1.9) (layers "B.Cu" "B.Paste" "B.Mask")
      (net 82 "SD_DAT1") (pinfunction "DAT1") (pintype "input"))
    (pad "9" smd rect (at -6.55 7.569 180) (size 0.7 1.9) (layers "B.Cu" "B.Paste" "B.Mask")
      (net 564 "Net-(J7-CD_SW1)") (pinfunction "CD_SW1") (pintype "passive"))
    (pad "SH" smd rect (at -8.1 6.518 180) (size 1.7 1.8) (layers "B.Cu" "B.Paste" "B.Mask")
      (net 9 "GND") (pinfunction "SH") (pintype "passive"))
    (pad "SH" smd rect (at -7.851 -3.081 180) (size 1.4 2.6) (layers "B.Cu" "B.Paste" "B.Mask")
      (net 9 "GND") (pinfunction "SH") (pintype "passive"))
    (pad "SH" smd rect (at 7.4 6.518 180) (size 1.7 1.8) (layers "B.Cu" "B.Paste" "B.Mask")
      (net 9 "GND") (pinfunction "SH") (pintype "passive"))
    (pad "SH" smd rect (at 7.849 -3.081 180) (size 1.4 2.6) (layers "B.Cu" "B.Paste" "B.Mask")
      (net 9 "GND") (pinfunction "SH") (pintype "passive"))
  )
	(footprint "data-center-rdimm-ddr4-tester-footprints:R_0603_1608Metric" (layer "B.Cu")
    (at 170.85 132.95 180)
    (descr "Resistor SMD 0603")
    (tags "resistor SMD 0603")
    (property "Author" "Antmicro")
    (property "License" "Apache-2.0")
    (property "MPN" "CR0603-FX-1001ELF")
    (property "Manufacturer" "Bourns")
    (property "Sheetfile" "ethernet.kicad_sch")
    (property "Sheetname" "Ethernet")
    (property "Tolerance" "1%")
    (property "Val" "1k")
    (property "ki_description" "1k resistor in 0603 package with 1% tolerance")
    (attr smd)
    (fp_text reference "R183" (at -1.44 -1.4) (layer "B.SilkS")
        (effects (font (size 0.7 0.7) (thickness 0.15)) (justify left bottom mirror))
    )
    (fp_text value "R_1k_0603" (at 0 -1.6) (layer "B.Fab") hide
        (effects (font (size 0.7 0.7) (thickness 0.15)) (justify left bottom mirror))
    )
    (fp_text user "${REFERENCE}" (at -1.25 -3.898) (layer "B.Fab") hide
        (effects (font (size 0.7 0.7) (thickness 0.15)) (justify left bottom mirror))
    )
    (fp_text user "Author: Antmicro" (at -1.25 -4.9) (layer "B.Fab") hide
        (effects (font (size 0.7 0.7) (thickness 0.15)) (justify left bottom mirror))
    )
    (fp_text user "License: Apache-2.0" (at -1.25 -5.9) (layer "B.Fab") hide
        (effects (font (size 0.7 0.7) (thickness 0.15)) (justify left bottom mirror))
    )
    (fp_line (start -0.3 -0.3) (end 0.3 -0.3)
      (stroke (width 0.15) (type solid)) (layer "B.SilkS"))
    (fp_line (start -0.3 0.3) (end 0.3 0.3)
      (stroke (width 0.15) (type solid)) (layer "B.SilkS"))
    (fp_rect (start -1.25 0.7) (end 1.25 -0.7)
      (stroke (width 0.05) (type solid)) (fill none) (layer "B.CrtYd"))
    (fp_rect (start -0.8 0.4) (end 0.8 -0.4)
      (stroke (width 0.15) (type solid)) (fill none) (layer "B.Fab"))
    (pad "1" smd roundrect (at -0.7 0 180) (size 0.6 0.8) (layers "B.Cu" "B.Paste" "B.Mask") (roundrect_rratio 0.2)
      (net 604 "GNDD") (pintype "passive"))
    (pad "2" smd roundrect (at 0.7 0 180) (size 0.6 0.8) (layers "B.Cu" "B.Paste" "B.Mask") (roundrect_rratio 0.2)
      (net 627 "Net-(IC2-Pad3)") (pintype "passive"))
  )
)
